(kicad_pcb
	(version 20241229)
	(generator "pcbnew")
	(generator_version "9.0")
	(general
		(thickness 1.62)
		(legacy_teardrops no)
	)
	(paper "A4")
	(title_block
		(title "OCuLink to 10GbE adapter")
		(date "2026-02-23")
		(rev "1.1.0")
		(company "Antmicro Ltd")
		(comment 1 "www.antmicro.com")
		(comment 9 "footprints 231-235 of 510")
	)
	(layers
		(0 "F.Cu" signal)
		(4 "In1.Cu" signal)
		(6 "In2.Cu" signal)
		(8 "In3.Cu" signal)
		(10 "In4.Cu" signal)
		(12 "In5.Cu" signal)
		(14 "In6.Cu" signal)
		(2 "B.Cu" signal)
		(9 "F.Adhes" user "F.Adhesive")
		(11 "B.Adhes" user "B.Adhesive")
		(13 "F.Paste" user)
		(15 "B.Paste" user)
		(5 "F.SilkS" user "F.Silkscreen")
		(7 "B.SilkS" user "B.Silkscreen")
		(1 "F.Mask" user)
		(3 "B.Mask" user)
		(17 "Dwgs.User" user "User.Drawings")
		(19 "Cmts.User" user "User.Comments")
		(21 "Eco1.User" user "User.Eco1")
		(23 "Eco2.User" user "User.Eco2")
		(25 "Edge.Cuts" user)
		(27 "Margin" user)
		(31 "F.CrtYd" user "F.Courtyard")
		(29 "B.CrtYd" user "B.Courtyard")
		(35 "F.Fab" user)
		(33 "B.Fab" user)
	)
	(footprint "antmicro-footprints:USON-10_2.5x1mm_P0.5mm"
		(layer "F.Cu")
		(at 97.248 59.985 -90)
		(descr "USON-10 2.5x1mm_ Pitch 0.5mm")
		(tags "USON-10 2.5x1mm Pitch 0.5mm")
		(property "Reference" "D8"
			(at 1.7 0.748 0)
			(layer "F.SilkS")
			(effects
				(font
					(size 0.7 0.7)
					(thickness 0.15)
				)
				(justify left bottom)
			)
		)
		(property "Value" "ESD204DQAR"
			(at 0.018 2.499 90)
			(layer "F.Fab")
			(hide yes)
			(effects
				(font
					(size 0.7 0.7)
					(thickness 0.15)
				)
				(justify right top)
			)
		)
		(property "Datasheet" "https://www.ti.com/lit/ds/symlink/esd204.pdf?ts=1706004844383&ref_url=https%253A%252F%252Fwww.ti.com%252Finterface%252Fdiodes%252Fesd-protection-diodes%252Fproducts.html"
			(at 0 0 90)
			(layer "F.Fab")
			(hide yes)
			(effects
				(font
					(size 1.27 1.27)
					(thickness 0.15)
				)
			)
		)
		(property "Description" "TVS diode array, 30 kV, USON-10, 3.6 V, 0.55 pF"
			(at 0 0 90)
			(layer "F.Fab")
			(hide yes)
			(effects
				(font
					(size 1.27 1.27)
					(thickness 0.15)
				)
			)
		)
		(property "MPN" "ESD204DQAR"
			(at 0 0 270)
			(unlocked yes)
			(layer "F.Fab")
			(hide yes)
			(effects
				(font
					(size 1 1)
					(thickness 0.15)
				)
			)
		)
		(property "Manufacturer" "Texas Instruments"
			(at 0 0 270)
			(unlocked yes)
			(layer "F.Fab")
			(hide yes)
			(effects
				(font
					(size 1 1)
					(thickness 0.15)
				)
			)
		)
		(property "Author" "Antmicro"
			(at 0 0 270)
			(unlocked yes)
			(layer "F.Fab")
			(hide yes)
			(effects
				(font
					(size 1 1)
					(thickness 0.15)
				)
			)
		)
		(property "License" "Apache-2.0"
			(at 0 0 270)
			(unlocked yes)
			(layer "F.Fab")
			(hide yes)
			(effects
				(font
					(size 1 1)
					(thickness 0.15)
				)
			)
		)
		(sheetname "/OCuLink/")
		(sheetfile "oculink.kicad_sch")
		(attr smd)
		(fp_line
			(start 0.498 1.398)
			(end -0.5 1.398)
			(stroke
				(width 0.15)
				(type solid)
			)
			(layer "F.SilkS")
		)
		(fp_line
			(start 0.498 -1.401)
			(end -0.5 -1.401)
			(stroke
				(width 0.15)
				(type solid)
			)
			(layer "F.SilkS")
		)
		(fp_circle
			(center -0.68 -1.27)
			(end -0.63 -1.27)
			(stroke
				(width 0.15)
				(type solid)
			)
			(fill yes)
			(layer "F.SilkS")
		)
		(fp_rect
			(start -0.8 -1.5)
			(end 0.8 1.499)
			(stroke
				(width 0.05)
				(type solid)
			)
			(fill no)
			(layer "F.CrtYd")
		)
		(fp_line
			(start -0.5 1.249)
			(end 0.498 1.249)
			(stroke
				(width 0.15)
				(type solid)
			)
			(layer "F.Fab")
		)
		(fp_line
			(start -0.5 -1)
			(end -0.5 1.249)
			(stroke
				(width 0.15)
				(type solid)
			)
			(layer "F.Fab")
		)
		(fp_line
			(start -0.25 -1.25)
			(end -0.5 -1)
			(stroke
				(width 0.15)
				(type solid)
			)
			(layer "F.Fab")
		)
		(fp_line
			(start 0.498 -1.25)
			(end 0.498 1.249)
			(stroke
				(width 0.15)
				(type solid)
			)
			(layer "F.Fab")
		)
		(fp_line
			(start 0.498 -1.25)
			(end -0.25 -1.25)
			(stroke
				(width 0.15)
				(type solid)
			)
			(layer "F.Fab")
		)
		(pad "1" smd roundrect
			(at -0.387 -1 180)
			(size 0.25 0.55)
			(layers "F.Cu" "F.Mask" "F.Paste")
			(roundrect_rratio 0.25)
			(net 21 "/OCuLink/PCIe_{x4}.TX2+")
			(pintype "passive")
		)
		(pad "2" smd roundrect
			(at -0.387 -0.5 180)
			(size 0.25 0.55)
			(layers "F.Cu" "F.Mask" "F.Paste")
			(roundrect_rratio 0.25)
			(net 22 "/OCuLink/PCIe_{x4}.TX2-")
			(pintype "passive")
		)
		(pad "3" smd roundrect
			(at -0.387 0 180)
			(size 0.4 0.55)
			(layers "F.Cu" "F.Mask" "F.Paste")
			(roundrect_rratio 0.25)
			(net 28 "GND")
			(pintype "power_in")
		)
		(pad "4" smd roundrect
			(at -0.387 0.498 180)
			(size 0.25 0.55)
			(layers "F.Cu" "F.Mask" "F.Paste")
			(roundrect_rratio 0.25)
			(net 25 "/OCuLink/PCIe_{x4}.TX3+")
			(pintype "passive")
		)
		(pad "5" smd roundrect
			(at -0.387 0.998 180)
			(size 0.25 0.55)
			(layers "F.Cu" "F.Mask" "F.Paste")
			(roundrect_rratio 0.25)
			(net 26 "/OCuLink/PCIe_{x4}.TX3-")
			(pintype "passive")
		)
		(pad "6" smd roundrect
			(at 0.385 0.998 180)
			(size 0.25 0.55)
			(layers "F.Cu" "F.Mask" "F.Paste")
			(roundrect_rratio 0.25)
			(net 26 "/OCuLink/PCIe_{x4}.TX3-")
			(pintype "passive")
		)
		(pad "7" smd roundrect
			(at 0.385 0.498 180)
			(size 0.25 0.55)
			(layers "F.Cu" "F.Mask" "F.Paste")
			(roundrect_rratio 0.25)
			(net 25 "/OCuLink/PCIe_{x4}.TX3+")
			(pintype "passive")
		)
		(pad "8" smd roundrect
			(at 0.385 0 180)
			(size 0.4 0.55)
			(layers "F.Cu" "F.Mask" "F.Paste")
			(roundrect_rratio 0.25)
			(net 28 "GND")
			(pintype "passive")
		)
		(pad "9" smd roundrect
			(at 0.385 -0.5 180)
			(size 0.25 0.55)
			(layers "F.Cu" "F.Mask" "F.Paste")
			(roundrect_rratio 0.25)
			(net 22 "/OCuLink/PCIe_{x4}.TX2-")
			(pintype "passive")
		)
		(pad "10" smd roundrect
			(at 0.385 -1 180)
			(size 0.25 0.55)
			(layers "F.Cu" "F.Mask" "F.Paste")
			(roundrect_rratio 0.25)
			(net 21 "/OCuLink/PCIe_{x4}.TX2+")
			(pintype "passive")
		)
	)
	(footprint "antmicro-footprints:VQFN-HR-9_2x1.5mm"
		(layer "F.Cu")
		(at 56.099999 95.75 -90)
		(property "Reference" "U5"
			(at -1.32 0.929999 180)
			(layer "F.SilkS")
			(effects
				(font
					(size 0.7 0.7)
					(thickness 0.15)
				)
				(justify right top)
			)
		)
		(property "Value" "TPS566231P"
			(at -1.45 2.45 90)
			(layer "F.Fab")
			(hide yes)
			(effects
				(font
					(size 0.7 0.7)
					(thickness 0.15)
				)
				(justify right top)
			)
		)
		(property "Datasheet" "https://www.ti.com/lit/ds/symlink/tps566231.pdf"
			(at 0 -0.045 90)
			(layer "F.Fab")
			(hide yes)
			(effects
				(font
					(size 0.7 0.7)
					(thickness 0.15)
				)
				(justify right top)
			)
		)
		(property "Description" "Switching Voltage Regulators 3-V to 18-V, 6-A synchronous buck converter"
			(at -1.45 3.65 90)
			(layer "F.Fab")
			(hide yes)
			(effects
				(font
					(size 0.7 0.7)
					(thickness 0.15)
				)
				(justify right top)
			)
		)
		(property "Manufacturer" "Texas Instruments"
			(at 0 0 270)
			(unlocked yes)
			(layer "F.Fab")
			(hide yes)
			(effects
				(font
					(size 1 1)
					(thickness 0.15)
				)
			)
		)
		(property "MPN" "TPS566231PRQFR"
			(at 0 0 270)
			(unlocked yes)
			(layer "F.Fab")
			(hide yes)
			(effects
				(font
					(size 1 1)
					(thickness 0.15)
				)
			)
		)
		(property "Author" "Antmicro"
			(at 0 0 270)
			(unlocked yes)
			(layer "F.Fab")
			(hide yes)
			(effects
				(font
					(size 1 1)
					(thickness 0.15)
				)
			)
		)
		(property "License" "Apache-2.0"
			(at 0 0 270)
			(unlocked yes)
			(layer "F.Fab")
			(hide yes)
			(effects
				(font
					(size 1 1)
					(thickness 0.15)
				)
			)
		)
		(sheetname "/Power/")
		(sheetfile "power.kicad_sch")
		(attr smd)
		(fp_line
			(start -1 0.945)
			(end -0.695 0.945)
			(stroke
				(width 0.15)
				(type solid)
			)
			(layer "F.SilkS")
		)
		(fp_line
			(start 1 0.945)
			(end 0.2 0.945)
			(stroke
				(width 0.15)
				(type solid)
			)
			(layer "F.SilkS")
		)
		(fp_line
			(start -1 -0.945)
			(end -0.695 -0.945)
			(stroke
				(width 0.15)
				(type solid)
			)
			(layer "F.SilkS")
		)
		(fp_line
			(start 1 -0.945)
			(end 0.695 -0.945)
			(stroke
				(width 0.15)
				(type solid)
			)
			(layer "F.SilkS")
		)
		(fp_circle
			(center -1.18 -0.77)
			(end -1.13 -0.77)
			(stroke
				(width 0.15)
				(type solid)
			)
			(fill yes)
			(layer "F.SilkS")
		)
		(fp_rect
			(start -1.3 -1.05)
			(end 1.3 1.05)
			(stroke
				(width 0.05)
				(type solid)
			)
			(fill no)
			(layer "F.CrtYd")
		)
		(fp_rect
			(start -1 -0.75)
			(end 1 0.75)
			(stroke
				(width 0.15)
				(type solid)
			)
			(fill no)
			(layer "F.Fab")
		)
		(pad "1" smd roundrect
			(at -0.925 -0.5 270)
			(size 0.55 0.25)
			(layers "F.Cu" "F.Mask" "F.Paste")
			(roundrect_rratio 0.125)
			(net 326 "/Power/DVDD_VCC")
			(pinfunction "V_{CC}")
			(pintype "passive")
		)
		(pad "2" smd roundrect
			(at -0.925 0 270)
			(size 0.55 0.25)
			(layers "F.Cu" "F.Mask" "F.Paste")
			(roundrect_rratio 0.125)
			(net 331 "/Power/DVDD_FB")
			(pinfunction "FB")
			(pintype "input")
		)
		(pad "3" smd roundrect
			(at -0.925 0.5 270)
			(size 0.55 0.25)
			(layers "F.Cu" "F.Mask" "F.Paste")
			(roundrect_rratio 0.125)
			(net 376 "/Power/DVDD_EN")
			(pinfunction "EN")
			(pintype "input")
		)
		(pad "4" smd roundrect
			(at -0.25 0.45 270)
			(size 0.25 1)
			(layers "F.Cu" "F.Mask" "F.Paste")
			(roundrect_rratio 0.125)
			(net 28 "GND")
			(pinfunction "PGND")
			(pintype "power_in")
		)
		(pad "5" smd roundrect
			(at 0.925 0.5 270)
			(size 0.55 0.25)
			(layers "F.Cu" "F.Mask" "F.Paste")
			(roundrect_rratio 0.125)
			(net 314 "VCC")
			(pinfunction "V_{IN}")
			(pintype "power_in")
		)
		(pad "6" smd roundrect
			(at 0.925 0 270)
			(size 0.55 0.25)
			(layers "F.Cu" "F.Mask" "F.Paste")
			(roundrect_rratio 0.125)
			(net 314 "VCC")
			(pinfunction "V_{IN}")
			(pintype "passive")
		)
		(pad "7" smd roundrect
			(at 0.925 -0.5 270)
			(size 0.55 0.25)
			(layers "F.Cu" "F.Mask" "F.Paste")
			(roundrect_rratio 0.125)
			(net 325 "/Power/DVDD_BST")
			(pinfunction "BST")
			(pintype "passive")
		)
		(pad "8" smd roundrect
			(at 0.25 -0.3 270)
			(size 0.25 1.3)
			(layers "F.Cu" "F.Mask" "F.Paste")
			(roundrect_rratio 0.125)
			(net 336 "/Power/DVDD_SW")
			(pinfunction "SW")
			(pintype "power_out")
		)
		(pad "9" smd roundrect
			(at -0.25 -0.675 270)
			(size 0.25 0.55)
			(layers "F.Cu" "F.Mask" "F.Paste")
			(roundrect_rratio 0.125)
			(net 378 "/Power/DVDD_PG")
			(pinfunction "PG")
			(pintype "passive")
		)
	)
	(footprint "antmicro-footprints:R_0402_1005Metric"
		(layer "F.Cu")
		(at 85.07 115)
		(descr "Resistor SMD 0402")
		(tags "resistor SMD 0402")
		(property "Reference" "RT1"
			(at -0.97 0.55 0)
			(layer "F.SilkS")
			(effects
				(font
					(size 0.7 0.7)
					(thickness 0.15)
				)
				(justify left top)
			)
		)
		(property "Value" "RT_NTC_10k_0402"
			(at -1.011843 1.772047 0)
			(layer "F.Fab")
			(hide yes)
			(effects
				(font
					(size 0.7 0.7)
					(thickness 0.15)
				)
				(justify left bottom)
			)
		)
		(property "Datasheet" "https://eu.mouser.com/datasheet/2/281/r44e-522712.pdf"
			(at 0 0 0)
			(layer "F.Fab")
			(hide yes)
			(effects
				(font
					(size 1.27 1.27)
					(thickness 0.15)
				)
			)
		)
		(property "Description" "10k NTC in 0402 package with 5V max voltage"
			(at 0 0 0)
			(layer "F.Fab")
			(hide yes)
			(effects
				(font
					(size 1.27 1.27)
					(thickness 0.15)
				)
			)
		)
		(property "MPN" "NCP15XH103F03RC"
			(at 0 0 0)
			(unlocked yes)
			(layer "F.Fab")
			(hide yes)
			(effects
				(font
					(size 1 1)
					(thickness 0.15)
				)
			)
		)
		(property "Manufacturer" "Murata"
			(at 0 0 0)
			(unlocked yes)
			(layer "F.Fab")
			(hide yes)
			(effects
				(font
					(size 1 1)
					(thickness 0.15)
				)
			)
		)
		(property "License" "Apache-2.0"
			(at 0 0 0)
			(unlocked yes)
			(layer "F.Fab")
			(hide yes)
			(effects
				(font
					(size 1 1)
					(thickness 0.15)
				)
			)
		)
		(property "Author" "Antmicro"
			(at 0 0 0)
			(unlocked yes)
			(layer "F.Fab")
			(hide yes)
			(effects
				(font
					(size 1 1)
					(thickness 0.15)
				)
			)
		)
		(property "Val" "10k"
			(at 0 0 0)
			(unlocked yes)
			(layer "F.Fab")
			(hide yes)
			(effects
				(font
					(size 1 1)
					(thickness 0.15)
				)
			)
		)
		(property "Voltage" "5V"
			(at 0 0 0)
			(unlocked yes)
			(layer "F.Fab")
			(hide yes)
			(effects
				(font
					(size 1 1)
					(thickness 0.15)
				)
			)
		)
		(sheetname "/Fan controller/")
		(sheetfile "fan-controller.kicad_sch")
		(attr smd exclude_from_pos_files exclude_from_bom dnp)
		(fp_rect
			(start -0.925 -0.47)
			(end 0.925 0.47)
			(stroke
				(width 0.05)
				(type default)
			)
			(fill no)
			(layer "F.CrtYd")
		)
		(fp_rect
			(start -0.5 -0.25)
			(end 0.5 0.25)
			(stroke
				(width 0.15)
				(type solid)
			)
			(fill no)
			(layer "F.Fab")
		)
		(pad "1" smd roundrect
			(at -0.48 0)
			(size 0.59 0.64)
			(layers "F.Cu" "F.Mask" "F.Paste")
			(roundrect_rratio 0.25)
			(net 397 "Net-(R175-Pad1)")
			(pintype "passive")
		)
		(pad "2" smd roundrect
			(at 0.48 0)
			(size 0.59 0.64)
			(layers "F.Cu" "F.Mask" "F.Paste")
			(roundrect_rratio 0.25)
			(net 28 "GND")
			(pintype "passive")
		)
	)
	(footprint "antmicro-footprints:R_0402_1005Metric"
		(layer "F.Cu")
		(at 99.35 103.3 180)
		(descr "Resistor SMD 0402")
		(tags "resistor SMD 0402")
		(property "Reference" "R80"
			(at 1.25 -15.05 0)
			(layer "F.SilkS")
			(effects
				(font
					(size 0.7 0.7)
					(thickness 0.15)
				)
				(justify left bottom)
			)
		)
		(property "Value" "R_100k_0402"
			(at -1.011843 1.772046 0)
			(layer "F.Fab")
			(hide yes)
			(effects
				(font
					(size 0.7 0.7)
					(thickness 0.15)
				)
				(justify right top)
			)
		)
		(property "Datasheet" "https://www.bourns.com/docs/product-datasheets/cr.pdf"
			(at 0 0 0)
			(layer "F.Fab")
			(hide yes)
			(effects
				(font
					(size 1.27 1.27)
					(thickness 0.15)
				)
			)
		)
		(property "Description" "SMD Chip Resistor, 100 kohm, ± 1%, 62.5 mW, 0402 [1005 Metric], Thick Film, General Purpose"
			(at 0 0 0)
			(layer "F.Fab")
			(hide yes)
			(effects
				(font
					(size 1.27 1.27)
					(thickness 0.15)
				)
			)
		)
		(property "MPN" "CR0402-FX-1003GLF"
			(at 0 0 180)
			(unlocked yes)
			(layer "F.Fab")
			(hide yes)
			(effects
				(font
					(size 1 1)
					(thickness 0.15)
				)
			)
		)
		(property "Manufacturer" "Bourns"
			(at 0 0 180)
			(unlocked yes)
			(layer "F.Fab")
			(hide yes)
			(effects
				(font
					(size 1 1)
					(thickness 0.15)
				)
			)
		)
		(property "License" "Apache-2.0"
			(at 0 0 180)
			(unlocked yes)
			(layer "F.Fab")
			(hide yes)
			(effects
				(font
					(size 1 1)
					(thickness 0.15)
				)
			)
		)
		(property "Author" "Antmicro"
			(at 0 0 180)
			(unlocked yes)
			(layer "F.Fab")
			(hide yes)
			(effects
				(font
					(size 1 1)
					(thickness 0.15)
				)
			)
		)
		(property "Val" "100k"
			(at 0 0 180)
			(unlocked yes)
			(layer "F.Fab")
			(hide yes)
			(effects
				(font
					(size 1 1)
					(thickness 0.15)
				)
			)
		)
		(property "Tolerance" "1%"
			(at 0 0 180)
			(unlocked yes)
			(layer "F.Fab")
			(hide yes)
			(effects
				(font
					(size 1 1)
					(thickness 0.15)
				)
			)
		)
		(sheetname "/X710-AT2 Misc/")
		(sheetfile "x710-at2-mics.kicad_sch")
		(attr smd)
		(fp_rect
			(start -0.925 -0.47)
			(end 0.925 0.47)
			(stroke
				(width 0.05)
				(type default)
			)
			(fill no)
			(layer "F.CrtYd")
		)
		(fp_rect
			(start -0.5 -0.25)
			(end 0.5 0.25)
			(stroke
				(width 0.15)
				(type solid)
			)
			(fill no)
			(layer "F.Fab")
		)
		(pad "1" smd roundrect
			(at -0.48 0 180)
			(size 0.59 0.64)
			(layers "F.Cu" "F.Mask" "F.Paste")
			(roundrect_rratio 0.25)
			(net 362 "/X710-AT2 Misc/NCSI.RXD_0")
			(pintype "passive")
		)
		(pad "2" smd roundrect
			(at 0.48 0 180)
			(size 0.59 0.64)
			(layers "F.Cu" "F.Mask" "F.Paste")
			(roundrect_rratio 0.25)
			(net 7 "+3V3")
			(pintype "passive")
		)
	)
	(footprint "antmicro-footprints:R_0402_1005Metric"
		(layer "F.Cu")
		(at 91.1 112.45 -90)
		(descr "Resistor SMD 0402")
		(tags "resistor SMD 0402")
		(property "Reference" "R171"
			(at 0.85 -0.4875 90)
			(layer "F.SilkS")
			(effects
				(font
					(size 0.7 0.7)
					(thickness 0.15)
				)
				(justify right bottom)
			)
		)
		(property "Value" "R_2k_0402"
			(at -1.011843 1.772046 90)
			(layer "F.Fab")
			(hide yes)
			(effects
				(font
					(size 0.7 0.7)
					(thickness 0.15)
				)
				(justify right top)
			)
		)
		(property "Datasheet" "https://www.bourns.com/docs/product-datasheets/cr.pdf"
			(at 0 0 90)
			(layer "F.Fab")
			(hide yes)
			(effects
				(font
					(size 1.27 1.27)
					(thickness 0.15)
				)
			)
		)
		(property "Description" "SMD Chip Resistor, 2 kohm, ± 1%, 62.5 mW, 0402 [1005 Metric], Thick Film, General Purpose"
			(at 0 0 90)
			(layer "F.Fab")
			(hide yes)
			(effects
				(font
					(size 1.27 1.27)
					(thickness 0.15)
				)
			)
		)
		(property "MPN" "CR0402-FX-2001GLF"
			(at 0 0 270)
			(unlocked yes)
			(layer "F.Fab")
			(hide yes)
			(effects
				(font
					(size 1 1)
					(thickness 0.15)
				)
			)
		)
		(property "Manufacturer" "Bourns"
			(at 0 0 270)
			(unlocked yes)
			(layer "F.Fab")
			(hide yes)
			(effects
				(font
					(size 1 1)
					(thickness 0.15)
				)
			)
		)
		(property "License" "Apache-2.0"
			(at 0 0 270)
			(unlocked yes)
			(layer "F.Fab")
			(hide yes)
			(effects
				(font
					(size 1 1)
					(thickness 0.15)
				)
			)
		)
		(property "Author" "Antmicro"
			(at 0 0 270)
			(unlocked yes)
			(layer "F.Fab")
			(hide yes)
			(effects
				(font
					(size 1 1)
					(thickness 0.15)
				)
			)
		)
		(property "Val" "2k"
			(at 0 0 270)
			(unlocked yes)
			(layer "F.Fab")
			(hide yes)
			(effects
				(font
					(size 1 1)
					(thickness 0.15)
				)
			)
		)
		(property "Tolerance" "1%"
			(at 0 0 270)
			(unlocked yes)
			(layer "F.Fab")
			(hide yes)
			(effects
				(font
					(size 1 1)
					(thickness 0.15)
				)
			)
		)
		(sheetname "/X710-AT2 Misc/")
		(sheetfile "x710-at2-mics.kicad_sch")
		(attr smd)
		(fp_rect
			(start -0.925 -0.47)
			(end 0.925 0.47)
			(stroke
				(width 0.05)
				(type default)
			)
			(fill no)
			(layer "F.CrtYd")
		)
		(fp_rect
			(start -0.5 -0.25)
			(end 0.5 0.25)
			(stroke
				(width 0.15)
				(type solid)
			)
			(fill no)
			(layer "F.Fab")
		)
		(pad "1" smd roundrect
			(at -0.48 0 270)
			(size 0.59 0.64)
			(layers "F.Cu" "F.Mask" "F.Paste")
			(roundrect_rratio 0.25)
			(net 380 "/X710-AT2 10GbE/~{PHY_RESET_3V3}")
			(pintype "passive")
		)
		(pad "2" smd roundrect
			(at 0.48 0 270)
			(size 0.59 0.64)
			(layers "F.Cu" "F.Mask" "F.Paste")
			(roundrect_rratio 0.25)
			(net 7 "+3V3")
			(pintype "passive")
		)
	)
)
